(kicad_pcb
	(version 20260206)
	(generator "pcbnew")
	(generator_version "10.0")
	(general
		(thickness 1.6)
		(legacy_teardrops no)
	)
	(paper "A4")
	(title_block
		(title "12092022_DA0F0TMDCD0_F0T_Management_Board_D_brd_V3_OCP.brd")
		(comment 1 "Grand Teton / footprints 160-161 of 1440")
	)
	(layers
		(0 "F.Cu" signal "TOP")
		(4 "In1.Cu" signal "GND")
		(6 "In2.Cu" signal "IN1")
		(8 "In3.Cu" signal "GND1")
		(10 "In4.Cu" signal "IN2")
		(12 "In5.Cu" signal "VCC")
		(14 "In6.Cu" signal "VCC1")
		(16 "In7.Cu" signal "IN3")
		(18 "In8.Cu" signal "GND2")
		(20 "In9.Cu" signal "IN4")
		(22 "In10.Cu" signal "GND3")
		(2 "B.Cu" signal "BOTTOM")
		(9 "F.Adhes" user "F.Adhesive")
		(11 "B.Adhes" user "B.Adhesive")
		(13 "F.Paste" user "Package Geometry/Pastemask Top")
		(15 "B.Paste" user "Package Geometry/Pastemask Bottom")
		(5 "F.SilkS" user "Ref Des/Silkscreen Top")
		(7 "B.SilkS" user "Ref Des/Silkscreen Bottom")
		(1 "F.Mask" user "Board Geometry/Soldermask Top")
		(3 "B.Mask" user "Board Geometry/Soldermask Bottom")
		(17 "Dwgs.User" user "User.Drawings")
		(19 "Cmts.User" user "User.Comments")
		(21 "Eco1.User" user "User.Eco1")
		(23 "Eco2.User" user "User.Eco2")
		(25 "Edge.Cuts" user "Board Geometry/Outline")
		(27 "Margin" user)
		(31 "F.CrtYd" user "Package Geometry/Place Bound Top")
		(29 "B.CrtYd" user "Package Geometry/Place Bound Bottom")
		(35 "F.Fab" user "Ref Des/Assembly Top")
		(33 "B.Fab" user "Ref Des/Assembly Bottom")
	)
	(footprint ""
		(layer "F.Cu")
		(at 6.050026 -103.925116)
		(property "Reference" "J7"
			(at -4.703826 -0.048514 0)
			(unlocked yes)
			(layer "F.SilkS")
			(effects
				(font
					(size 0.7874 0.5842)
					(thickness 0.1524)
				)
				(justify left)
			)
		)
		(property "Value" ""
			(at 0 0 0)
			(layer "F.Fab")
			(effects
				(font
					(size 1.27 1.27)
				)
			)
		)
		(duplicate_pad_numbers_are_jumpers no)
		(fp_line
			(start -1.249934 -1.320038)
			(end 1.249934 -1.320038)
			(stroke
				(width 0.1524)
				(type default)
			)
			(layer "F.SilkS")
		)
		(fp_line
			(start -1.249934 19.100038)
			(end -1.249934 -1.320038)
			(stroke
				(width 0.1524)
				(type default)
			)
			(layer "F.SilkS")
		)
		(fp_line
			(start 1.249934 -1.320038)
			(end 1.249934 19.100038)
			(stroke
				(width 0.1524)
				(type default)
			)
			(layer "F.SilkS")
		)
		(fp_line
			(start 1.249934 19.100038)
			(end -1.249934 19.100038)
			(stroke
				(width 0.1524)
				(type default)
			)
			(layer "F.SilkS")
		)
		(fp_poly
			(pts
				(xy -2.7432 0.63881) (xy -2.7432 -0.63881) (xy -1.465834 0)
			)
			(stroke
				(width 0)
				(type default)
			)
			(fill yes)
			(layer "F.SilkS")
		)
		(fp_line
			(start -1.249934 -1.320038)
			(end 1.249934 -1.320038)
			(stroke
				(width 0.1)
				(type default)
			)
			(layer "F.Fab")
		)
		(fp_line
			(start -1.249934 19.100038)
			(end -1.249934 -1.320038)
			(stroke
				(width 0.1)
				(type default)
			)
			(layer "F.Fab")
		)
		(fp_line
			(start 1.249934 -1.320038)
			(end 1.249934 19.100038)
			(stroke
				(width 0.1)
				(type default)
			)
			(layer "F.Fab")
		)
		(fp_line
			(start 1.249934 19.100038)
			(end -1.249934 19.100038)
			(stroke
				(width 0.1)
				(type default)
			)
			(layer "F.Fab")
		)
		(fp_poly
			(pts
				(xy -2.7432 0.63881) (xy -2.7432 -0.63881) (xy -1.465834 0)
			)
			(stroke
				(width 0)
				(type default)
			)
			(fill yes)
			(layer "F.Fab")
		)
		(fp_text user "8"
			(at -1.7526 17.80667 0)
			(unlocked yes)
			(layer "F.SilkS")
			(effects
				(font
					(size 0.7874 0.5842)
					(thickness 0.1524)
				)
			)
		)
		(fp_text user "1"
			(at -1.401826 -0.340614 0)
			(unlocked yes)
			(layer "B.SilkS")
			(effects
				(font
					(size 0.7874 0.5842)
					(thickness 0.1524)
				)
				(justify mirror)
			)
		)
		(fp_text user "8"
			(at -1.1938 17.80667 0)
			(unlocked yes)
			(layer "B.SilkS")
			(effects
				(font
					(size 0.7874 0.5842)
					(thickness 0.1524)
				)
				(justify mirror)
			)
		)
		(fp_text user "8"
			(at -1.1938 17.80667 0)
			(unlocked yes)
			(layer "B.Fab")
			(effects
				(font
					(size 0.7874 0.5842)
					(thickness 0.1524)
				)
				(justify mirror)
			)
		)
		(fp_text user "1"
			(at -1.1176 -0.02413 0)
			(unlocked yes)
			(layer "B.Fab")
			(effects
				(font
					(size 0.7874 0.5842)
					(thickness 0.1524)
				)
				(justify mirror)
			)
		)
		(fp_text user "8"
			(at -1.7526 17.80667 0)
			(unlocked yes)
			(layer "F.Fab")
			(effects
				(font
					(size 0.7874 0.5842)
					(thickness 0.1524)
				)
			)
		)
		(pad "1" thru_hole rect
			(at 0 0)
			(size 1.5494 1.5494)
			(drill 1.0414)
			(layers "*.Cu" "*.Mask")
			(remove_unused_layers no)
			(net "J7_P1")
			(clearance 0)
			(padstack
				(mode front_inner_back)
				(layer "Inner"
					(shape circle)
					(size 1.5494 1.5494)
					(clearance 0)
				)
				(layer "B.Cu"
					(shape rect)
					(size 1.5494 1.5494)
					(clearance 0)
				)
			)
		)
		(pad "2" thru_hole circle
			(at 0 2.54)
			(size 1.5494 1.5494)
			(drill 1.0414)
			(layers "*.Cu" "*.Mask")
			(remove_unused_layers no)
			(net "JTAG_SCM_CONN_TDO")
			(clearance 0)
		)
		(pad "3" thru_hole circle
			(at 0 5.08)
			(size 1.5494 1.5494)
			(drill 1.0414)
			(layers "*.Cu" "*.Mask")
			(remove_unused_layers no)
			(net "JTAG_SCM_CONN_TDI")
			(clearance 0)
		)
		(pad "4" thru_hole circle
			(at 0 7.62)
			(size 1.5494 1.5494)
			(drill 1.0414)
			(layers "*.Cu" "*.Mask")
			(remove_unused_layers no)
			(net "JTAG_SCM_PLD_R1_JTAGEN")
			(clearance 0)
		)
		(pad "5" thru_hole circle
			(at 0 10.16)
			(size 1.5494 1.5494)
			(drill 1.0414)
			(layers "*.Cu" "*.Mask")
			(remove_unused_layers no)
			(net "TP_PLD_CONN_P5")
			(clearance 0)
		)
		(pad "6" thru_hole circle
			(at 0 12.7)
			(size 1.5494 1.5494)
			(drill 1.0414)
			(layers "*.Cu" "*.Mask")
			(remove_unused_layers no)
			(net "JTAG_SCM_CONN_TMS")
			(clearance 0)
		)
		(pad "7" thru_hole circle
			(at 0 15.24)
			(size 1.5494 1.5494)
			(drill 1.0414)
			(layers "*.Cu" "*.Mask")
			(remove_unused_layers no)
			(net "GND")
			(clearance 0)
		)
		(pad "8" thru_hole circle
			(at 0 17.78)
			(size 1.5494 1.5494)
			(drill 1.0414)
			(layers "*.Cu" "*.Mask")
			(remove_unused_layers no)
			(net "JTAG_SCM_CONN_TCK")
			(clearance 0)
		)
	)
	(footprint ""
		(layer "F.Cu")
		(at 39.4462 -26.1112 90)
		(property "Reference" "R392"
			(at 0 0 90)
			(layer "F.SilkS")
			(hide yes)
			(effects
				(font
					(size 1.27 1.27)
				)
			)
		)
		(property "Value" ""
			(at 0 0 90)
			(layer "F.Fab")
			(effects
				(font
					(size 1.27 1.27)
				)
			)
		)
		(duplicate_pad_numbers_are_jumpers no)
		(fp_line
			(start 0.7874 -0.4064)
			(end 0.7874 0.4064)
			(stroke
				(width 0.1524)
				(type default)
			)
			(layer "F.SilkS")
		)
		(fp_line
			(start -0.7874 -0.4064)
			(end 0.7874 -0.4064)
			(stroke
				(width 0.1524)
				(type default)
			)
			(layer "F.SilkS")
		)
		(fp_line
			(start 0.7874 0.4064)
			(end -0.7874 0.4064)
			(stroke
				(width 0.1524)
				(type default)
			)
			(layer "F.SilkS")
		)
		(fp_line
			(start -0.7874 0.4064)
			(end -0.7874 -0.4064)
			(stroke
				(width 0.1524)
				(type default)
			)
			(layer "F.SilkS")
		)
		(fp_line
			(start -0.12065 -0.305054)
			(end -0.12065 -0.2794)
			(stroke
				(width 0.1)
				(type default)
			)
			(layer "F.Fab")
		)
		(fp_line
			(start -0.67945 -0.305054)
			(end -0.12065 -0.305054)
			(stroke
				(width 0.1)
				(type default)
			)
			(layer "F.Fab")
		)
		(fp_line
			(start 0.67945 -0.3048)
			(end 0.67945 0.3048)
			(stroke
				(width 0.1)
				(type default)
			)
			(layer "F.Fab")
		)
		(fp_line
			(start 0.12065 -0.3048)
			(end 0.67945 -0.3048)
			(stroke
				(width 0.1)
				(type default)
			)
			(layer "F.Fab")
		)
		(fp_line
			(start 0.12065 -0.2794)
			(end 0.12065 -0.3048)
			(stroke
				(width 0.1)
				(type default)
			)
			(layer "F.Fab")
		)
		(fp_line
			(start -0.12065 -0.2794)
			(end 0.12065 -0.2794)
			(stroke
				(width 0.1)
				(type default)
			)
			(layer "F.Fab")
		)
		(fp_line
			(start 0.120396 0.2794)
			(end -0.12065 0.2794)
			(stroke
				(width 0.1)
				(type default)
			)
			(layer "F.Fab")
		)
		(fp_line
			(start -0.12065 0.2794)
			(end -0.12065 0.3048)
			(stroke
				(width 0.1)
				(type default)
			)
			(layer "F.Fab")
		)
		(fp_line
			(start 0.67945 0.3048)
			(end 0.120396 0.3048)
			(stroke
				(width 0.1)
				(type default)
			)
			(layer "F.Fab")
		)
		(fp_line
			(start 0.120396 0.3048)
			(end 0.120396 0.2794)
			(stroke
				(width 0.1)
				(type default)
			)
			(layer "F.Fab")
		)
		(fp_line
			(start -0.12065 0.3048)
			(end -0.67945 0.3048)
			(stroke
				(width 0.1)
				(type default)
			)
			(layer "F.Fab")
		)
		(fp_line
			(start -0.67945 0.3048)
			(end -0.67945 -0.305054)
			(stroke
				(width 0.1)
				(type default)
			)
			(layer "F.Fab")
		)
		(pad "1" smd circle
			(at -0.40005 0 90)
			(size 0 0)
			(layers "F.Cu" "F.Mask" "F.Paste")
			(net "RMII_OCP_RCLKI_ISO")
		)
		(pad "2" smd circle
			(at 0.40005 0 90)
			(size 0 0)
			(layers "F.Cu" "F.Mask" "F.Paste")
			(net "RMII_OCP_RCLKI_R_ISO")
		)
	)
)
